# S9S_MB_2U (Grand Teton) — schematic netlist excerpt (pin names and nets, part order shuffled) for the footprints in the layout excerpt that follows; sources: Cadence DE-HDL packaged netlist, KiCad conversion of 03242023_DA0F0TMBIJ0_F0T_Motherboard_J_brd_V01_OCP.brd

C1274  Q_CAP  0.1UF 25V 10% X7R  pkg 0402  page 155 : A = P3V3_AUX ; B = GND
R3513  Q_RES  54.9K 1% CHIP  pkg 0402LF  page 148 : A = FM_GPU_PWRGD ; B = GND

(kicad_pcb
	(version 20260206)
	(generator "pcbnew")
	(generator_version "10.0")
	(general
		(thickness 1.6)
		(legacy_teardrops no)
	)
	(paper "A4")
	(title_block
		(title "03242023_DA0F0TMBIJ0_F0T_Motherboard_J_brd_V01_OCP.brd")
		(comment 1 "Grand Teton / footprints 2603-2604 of 6105")
	)
	(layers
		(0 "F.Cu" signal "TOP")
		(4 "In1.Cu" signal "GND")
		(6 "In2.Cu" signal "IN1")
		(8 "In3.Cu" signal "GND1")
		(10 "In4.Cu" signal "IN2")
		(12 "In5.Cu" signal "GND2")
		(14 "In6.Cu" signal "IN3")
		(16 "In7.Cu" signal "GND3")
		(18 "In8.Cu" signal "VCC")
		(20 "In9.Cu" signal "VCC1")
		(22 "In10.Cu" signal "GND4")
		(24 "In11.Cu" signal "IN4")
		(26 "In12.Cu" signal "GND5")
		(28 "In13.Cu" signal "IN5")
		(30 "In14.Cu" signal "GND6")
		(32 "In15.Cu" signal "IN6")
		(34 "In16.Cu" signal "GND7")
		(2 "B.Cu" signal "BOTTOM")
		(9 "F.Adhes" user "F.Adhesive")
		(11 "B.Adhes" user "B.Adhesive")
		(13 "F.Paste" user "Package Geometry/Pastemask Top")
		(15 "B.Paste" user "Package Geometry/Pastemask Bottom")
		(5 "F.SilkS" user "Ref Des/Silkscreen Top")
		(7 "B.SilkS" user "Ref Des/Silkscreen Bottom")
		(1 "F.Mask" user "Board Geometry/Soldermask Top")
		(3 "B.Mask" user "Board Geometry/Soldermask Bottom")
		(17 "Dwgs.User" user "User.Drawings")
		(19 "Cmts.User" user "User.Comments")
		(21 "Eco1.User" user "User.Eco1")
		(23 "Eco2.User" user "User.Eco2")
		(25 "Edge.Cuts" user "Board Geometry/Outline")
		(27 "Margin" user)
		(31 "F.CrtYd" user "Package Geometry/Place Bound Top")
		(29 "B.CrtYd" user "Package Geometry/Place Bound Bottom")
		(35 "F.Fab" user "Ref Des/Assembly Top")
		(33 "B.Fab" user "Ref Des/Assembly Bottom")
	)
	(footprint ""
		(layer "F.Cu")
		(at 211.99221 -26.868374 -90)
		(property "Reference" "C1274"
			(at 0 0 270)
			(layer "F.SilkS")
			(hide yes)
			(effects
				(font
					(size 1.27 1.27)
				)
			)
		)
		(property "Value" ""
			(at 0 0 270)
			(layer "F.Fab")
			(effects
				(font
					(size 1.27 1.27)
				)
			)
		)
		(duplicate_pad_numbers_are_jumpers no)
		(fp_line
			(start -0.7874 0.4064)
			(end -0.7874 -0.4064)
			(stroke
				(width 0.1524)
				(type default)
			)
			(layer "F.SilkS")
		)
		(fp_line
			(start 0.7874 0.4064)
			(end -0.7874 0.4064)
			(stroke
				(width 0.1524)
				(type default)
			)
			(layer "F.SilkS")
		)
		(fp_line
			(start -0.7874 -0.4064)
			(end 0.7874 -0.4064)
			(stroke
				(width 0.1524)
				(type default)
			)
			(layer "F.SilkS")
		)
		(fp_line
			(start 0.7874 -0.4064)
			(end 0.7874 0.4064)
			(stroke
				(width 0.1524)
				(type default)
			)
			(layer "F.SilkS")
		)
		(fp_line
			(start -0.67945 0.3048)
			(end -0.67945 -0.305054)
			(stroke
				(width 0.1)
				(type default)
			)
			(layer "F.Fab")
		)
		(fp_line
			(start -0.12065 0.3048)
			(end -0.67945 0.3048)
			(stroke
				(width 0.1)
				(type default)
			)
			(layer "F.Fab")
		)
		(fp_line
			(start 0.120396 0.3048)
			(end 0.120396 0.2794)
			(stroke
				(width 0.1)
				(type default)
			)
			(layer "F.Fab")
		)
		(fp_line
			(start 0.67945 0.3048)
			(end 0.120396 0.3048)
			(stroke
				(width 0.1)
				(type default)
			)
			(layer "F.Fab")
		)
		(fp_line
			(start -0.12065 0.2794)
			(end -0.12065 0.3048)
			(stroke
				(width 0.1)
				(type default)
			)
			(layer "F.Fab")
		)
		(fp_line
			(start 0.120396 0.2794)
			(end -0.12065 0.2794)
			(stroke
				(width 0.1)
				(type default)
			)
			(layer "F.Fab")
		)
		(fp_line
			(start -0.12065 -0.2794)
			(end 0.12065 -0.2794)
			(stroke
				(width 0.1)
				(type default)
			)
			(layer "F.Fab")
		)
		(fp_line
			(start 0.12065 -0.2794)
			(end 0.12065 -0.3048)
			(stroke
				(width 0.1)
				(type default)
			)
			(layer "F.Fab")
		)
		(fp_line
			(start 0.12065 -0.3048)
			(end 0.67945 -0.3048)
			(stroke
				(width 0.1)
				(type default)
			)
			(layer "F.Fab")
		)
		(fp_line
			(start 0.67945 -0.3048)
			(end 0.67945 0.3048)
			(stroke
				(width 0.1)
				(type default)
			)
			(layer "F.Fab")
		)
		(fp_line
			(start -0.67945 -0.305054)
			(end -0.12065 -0.305054)
			(stroke
				(width 0.1)
				(type default)
			)
			(layer "F.Fab")
		)
		(fp_line
			(start -0.12065 -0.305054)
			(end -0.12065 -0.2794)
			(stroke
				(width 0.1)
				(type default)
			)
			(layer "F.Fab")
		)
		(pad "1" smd circle
			(at -0.40005 0 270)
			(size 0 0)
			(layers "F.Cu" "F.Mask" "F.Paste")
			(net "P3V3_AUX")
		)
		(pad "2" smd circle
			(at 0.40005 0 270)
			(size 0 0)
			(layers "F.Cu" "F.Mask" "F.Paste")
			(net "GND")
		)
	)
	(footprint ""
		(layer "F.Cu")
		(at 24.046942 -416.143948 180)
		(property "Reference" "R3513"
			(at 0 0 180)
			(layer "F.SilkS")
			(hide yes)
			(effects
				(font
					(size 1.27 1.27)
				)
			)
		)
		(property "Value" ""
			(at 0 0 180)
			(layer "F.Fab")
			(effects
				(font
					(size 1.27 1.27)
				)
			)
		)
		(duplicate_pad_numbers_are_jumpers no)
		(fp_line
			(start 0.7874 0.4064)
			(end -0.7874 0.4064)
			(stroke
				(width 0.1524)
				(type default)
			)
			(layer "F.SilkS")
		)
		(fp_line
			(start 0.7874 -0.4064)
			(end 0.7874 0.4064)
			(stroke
				(width 0.1524)
				(type default)
			)
			(layer "F.SilkS")
		)
		(fp_line
			(start -0.7874 0.4064)
			(end -0.7874 -0.4064)
			(stroke
				(width 0.1524)
				(type default)
			)
			(layer "F.SilkS")
		)
		(fp_line
			(start -0.7874 -0.4064)
			(end 0.7874 -0.4064)
			(stroke
				(width 0.1524)
				(type default)
			)
			(layer "F.SilkS")
		)
		(fp_line
			(start 0.67945 0.3048)
			(end 0.120396 0.3048)
			(stroke
				(width 0.1)
				(type default)
			)
			(layer "F.Fab")
		)
		(fp_line
			(start 0.67945 -0.3048)
			(end 0.67945 0.3048)
			(stroke
				(width 0.1)
				(type default)
			)
			(layer "F.Fab")
		)
		(fp_line
			(start 0.12065 -0.2794)
			(end 0.12065 -0.3048)
			(stroke
				(width 0.1)
				(type default)
			)
			(layer "F.Fab")
		)
		(fp_line
			(start 0.12065 -0.3048)
			(end 0.67945 -0.3048)
			(stroke
				(width 0.1)
				(type default)
			)
			(layer "F.Fab")
		)
		(fp_line
			(start 0.120396 0.3048)
			(end 0.120396 0.2794)
			(stroke
				(width 0.1)
				(type default)
			)
			(layer "F.Fab")
		)
		(fp_line
			(start 0.120396 0.2794)
			(end -0.12065 0.2794)
			(stroke
				(width 0.1)
				(type default)
			)
			(layer "F.Fab")
		)
		(fp_line
			(start -0.12065 0.3048)
			(end -0.67945 0.3048)
			(stroke
				(width 0.1)
				(type default)
			)
			(layer "F.Fab")
		)
		(fp_line
			(start -0.12065 0.2794)
			(end -0.12065 0.3048)
			(stroke
				(width 0.1)
				(type default)
			)
			(layer "F.Fab")
		)
		(fp_line
			(start -0.12065 -0.2794)
			(end 0.12065 -0.2794)
			(stroke
				(width 0.1)
				(type default)
			)
			(layer "F.Fab")
		)
		(fp_line
			(start -0.12065 -0.305054)
			(end -0.12065 -0.2794)
			(stroke
				(width 0.1)
				(type default)
			)
			(layer "F.Fab")
		)
		(fp_line
			(start -0.67945 0.3048)
			(end -0.67945 -0.305054)
			(stroke
				(width 0.1)
				(type default)
			)
			(layer "F.Fab")
		)
		(fp_line
			(start -0.67945 -0.305054)
			(end -0.12065 -0.305054)
			(stroke
				(width 0.1)
				(type default)
			)
			(layer "F.Fab")
		)
		(pad "1" smd circle
			(at -0.40005 0 180)
			(size 0 0)
			(layers "F.Cu" "F.Mask" "F.Paste")
			(net "FM_GPU_PWRGD")
		)
		(pad "2" smd circle
			(at 0.40005 0 180)
			(size 0 0)
			(layers "F.Cu" "F.Mask" "F.Paste")
			(net "GND")
		)
	)
)
